(kicad_pcb
	(version 20260206)
	(generator "pcbnew")
	(generator_version "10.0")
	(general
		(thickness 1.6)
		(legacy_teardrops no)
	)
	(paper "A4")
	(title_block
		(title "01162023_DA0F0TEBIF0_F0T_Expander_BD_F_brd_V02_OCP.brd")
		(comment 1 "Grand Teton / footprints 1597-1603 of 9728")
	)
	(layers
		(0 "F.Cu" signal "TOP")
		(4 "In1.Cu" signal "GND")
		(6 "In2.Cu" signal "VCC")
		(8 "In3.Cu" signal "VCC1")
		(10 "In4.Cu" signal "GND1")
		(12 "In5.Cu" signal "IN1")
		(14 "In6.Cu" signal "GND2")
		(16 "In7.Cu" signal "IN2")
		(18 "In8.Cu" signal "GND3")
		(20 "In9.Cu" signal "IN3")
		(22 "In10.Cu" signal "GND4")
		(24 "In11.Cu" signal "IN4")
		(26 "In12.Cu" signal "GND5")
		(28 "In13.Cu" signal "IN5")
		(30 "In14.Cu" signal "GND6")
		(32 "In15.Cu" signal "IN6")
		(34 "In16.Cu" signal "GND7")
		(2 "B.Cu" signal "BOTTOM")
		(9 "F.Adhes" user "F.Adhesive")
		(11 "B.Adhes" user "B.Adhesive")
		(13 "F.Paste" user "Package Geometry/Pastemask Top")
		(15 "B.Paste" user "Package Geometry/Pastemask Bottom")
		(5 "F.SilkS" user "Ref Des/Silkscreen Top")
		(7 "B.SilkS" user "Ref Des/Silkscreen Bottom")
		(1 "F.Mask" user "Board Geometry/Soldermask Top")
		(3 "B.Mask" user "Board Geometry/Soldermask Bottom")
		(17 "Dwgs.User" user "User.Drawings")
		(19 "Cmts.User" user "User.Comments")
		(21 "Eco1.User" user "User.Eco1")
		(23 "Eco2.User" user "User.Eco2")
		(25 "Edge.Cuts" user "Board Geometry/Outline")
		(27 "Margin" user)
		(31 "F.CrtYd" user "Package Geometry/Place Bound Top")
		(29 "B.CrtYd" user "Package Geometry/Place Bound Bottom")
		(35 "F.Fab" user "Ref Des/Assembly Top")
		(33 "B.Fab" user "Ref Des/Assembly Bottom")
	)
	(footprint ""
		(layer "F.Cu")
		(at 25.341834 -261.026402 180)
		(property "Reference" "C3070"
			(at 0 0 180)
			(layer "F.SilkS")
			(hide yes)
			(effects
				(font
					(size 1.27 1.27)
				)
			)
		)
		(property "Value" ""
			(at 0 0 180)
			(layer "F.Fab")
			(effects
				(font
					(size 1.27 1.27)
				)
			)
		)
		(duplicate_pad_numbers_are_jumpers no)
		(fp_line
			(start 1.2954 0.5842)
			(end -1.2954 0.5842)
			(stroke
				(width 0.1524)
				(type default)
			)
			(layer "F.SilkS")
		)
		(fp_line
			(start 1.2954 -0.5842)
			(end 1.2954 0.5842)
			(stroke
				(width 0.1524)
				(type default)
			)
			(layer "F.SilkS")
		)
		(fp_line
			(start -1.2954 0.5842)
			(end -1.2954 -0.5842)
			(stroke
				(width 0.1524)
				(type default)
			)
			(layer "F.SilkS")
		)
		(fp_line
			(start -1.2954 -0.5842)
			(end 1.2954 -0.5842)
			(stroke
				(width 0.1524)
				(type default)
			)
			(layer "F.SilkS")
		)
		(fp_line
			(start 1.1938 0.4064)
			(end 0.8636 0.4064)
			(stroke
				(width 0.1)
				(type default)
			)
			(layer "F.Fab")
		)
		(fp_line
			(start 1.1938 -0.4064)
			(end 1.1938 0.4064)
			(stroke
				(width 0.1)
				(type default)
			)
			(layer "F.Fab")
		)
		(fp_line
			(start 0.8636 0.4572)
			(end -0.8636 0.4572)
			(stroke
				(width 0.1)
				(type default)
			)
			(layer "F.Fab")
		)
		(fp_line
			(start 0.8636 0.4064)
			(end 0.8636 0.4572)
			(stroke
				(width 0.1)
				(type default)
			)
			(layer "F.Fab")
		)
		(fp_line
			(start 0.8636 -0.4064)
			(end 1.1938 -0.4064)
			(stroke
				(width 0.1)
				(type default)
			)
			(layer "F.Fab")
		)
		(fp_line
			(start 0.8636 -0.4572)
			(end 0.8636 -0.4064)
			(stroke
				(width 0.1)
				(type default)
			)
			(layer "F.Fab")
		)
		(fp_line
			(start -0.8636 0.4572)
			(end -0.8636 0.4064)
			(stroke
				(width 0.1)
				(type default)
			)
			(layer "F.Fab")
		)
		(fp_line
			(start -0.8636 0.4064)
			(end -1.1938 0.4064)
			(stroke
				(width 0.1)
				(type default)
			)
			(layer "F.Fab")
		)
		(fp_line
			(start -0.8636 -0.4064)
			(end -0.8636 -0.4572)
			(stroke
				(width 0.1)
				(type default)
			)
			(layer "F.Fab")
		)
		(fp_line
			(start -0.8636 -0.4572)
			(end 0.8636 -0.4572)
			(stroke
				(width 0.1)
				(type default)
			)
			(layer "F.Fab")
		)
		(fp_line
			(start -1.1938 0.4064)
			(end -1.1938 -0.4064)
			(stroke
				(width 0.1)
				(type default)
			)
			(layer "F.Fab")
		)
		(fp_line
			(start -1.1938 -0.4064)
			(end -0.8636 -0.4064)
			(stroke
				(width 0.1)
				(type default)
			)
			(layer "F.Fab")
		)
		(pad "1" smd rect
			(at -0.7366 0 90)
			(size 0.7112 0.8128)
			(layers "F.Cu" "F.Mask" "F.Paste")
			(net "P1V8_VDDA_PEX0")
		)
		(pad "2" smd rect
			(at 0.7366 0 90)
			(size 0.7112 0.8128)
			(layers "F.Cu" "F.Mask" "F.Paste")
			(net "GND")
		)
	)
	(footprint ""
		(layer "F.Cu")
		(at 110.745016 -149.428454 -90)
		(property "Reference" "PL4"
			(at 7.442454 7.060946 90)
			(unlocked yes)
			(layer "F.SilkS")
			(effects
				(font
					(size 0.7874 0.5842)
					(thickness 0.1524)
				)
				(justify left)
			)
		)
		(property "Value" ""
			(at 0 0 270)
			(layer "F.Fab")
			(effects
				(font
					(size 1.27 1.27)
				)
			)
		)
		(duplicate_pad_numbers_are_jumpers no)
		(fp_line
			(start -7.4422 6.400038)
			(end -7.4422 -6.400038)
			(stroke
				(width 0.1524)
				(type default)
			)
			(layer "F.SilkS")
		)
		(fp_line
			(start 7.4422 6.400038)
			(end -7.4422 6.400038)
			(stroke
				(width 0.1524)
				(type default)
			)
			(layer "F.SilkS")
		)
		(fp_line
			(start -7.4422 -6.400038)
			(end 7.4422 -6.400038)
			(stroke
				(width 0.1524)
				(type default)
			)
			(layer "F.SilkS")
		)
		(fp_line
			(start 7.4422 -6.400038)
			(end 7.4422 6.400038)
			(stroke
				(width 0.1524)
				(type default)
			)
			(layer "F.SilkS")
		)
		(fp_line
			(start -6.862064 6.400038)
			(end 6.938264 6.400038)
			(stroke
				(width 0.1)
				(type default)
			)
			(layer "F.Fab")
		)
		(fp_line
			(start 6.938264 6.400038)
			(end 6.938264 -6.400038)
			(stroke
				(width 0.1)
				(type default)
			)
			(layer "F.Fab")
		)
		(fp_line
			(start -6.862064 -6.400038)
			(end -6.862064 6.400038)
			(stroke
				(width 0.1)
				(type default)
			)
			(layer "F.Fab")
		)
		(fp_line
			(start 6.938264 -6.400038)
			(end -6.862064 -6.400038)
			(stroke
				(width 0.1)
				(type default)
			)
			(layer "F.Fab")
		)
		(pad "1" smd rect
			(at -5.650484 0 270)
			(size 3.302 4.29768)
			(layers "F.Cu" "F.Mask" "F.Paste")
			(net "SW_P3V3_AUX_PH")
		)
		(pad "2" smd rect
			(at 5.650484 0 270)
			(size 3.302 4.29768)
			(layers "F.Cu" "F.Mask" "F.Paste")
			(net "P3V3_AUX")
		)
	)
	(footprint ""
		(layer "F.Cu")
		(at 363.474 -201.803 180)
		(property "Reference" "R4682"
			(at 0 0 180)
			(layer "F.SilkS")
			(hide yes)
			(effects
				(font
					(size 1.27 1.27)
				)
			)
		)
		(property "Value" ""
			(at 0 0 180)
			(layer "F.Fab")
			(effects
				(font
					(size 1.27 1.27)
				)
			)
		)
		(duplicate_pad_numbers_are_jumpers no)
		(fp_line
			(start 0.7874 0.4064)
			(end -0.7874 0.4064)
			(stroke
				(width 0.1524)
				(type default)
			)
			(layer "F.SilkS")
		)
		(fp_line
			(start 0.7874 -0.4064)
			(end 0.7874 0.4064)
			(stroke
				(width 0.1524)
				(type default)
			)
			(layer "F.SilkS")
		)
		(fp_line
			(start -0.7874 0.4064)
			(end -0.7874 -0.4064)
			(stroke
				(width 0.1524)
				(type default)
			)
			(layer "F.SilkS")
		)
		(fp_line
			(start -0.7874 -0.4064)
			(end 0.7874 -0.4064)
			(stroke
				(width 0.1524)
				(type default)
			)
			(layer "F.SilkS")
		)
		(fp_line
			(start 0.67945 0.3048)
			(end 0.120396 0.3048)
			(stroke
				(width 0.1)
				(type default)
			)
			(layer "F.Fab")
		)
		(fp_line
			(start 0.67945 -0.3048)
			(end 0.67945 0.3048)
			(stroke
				(width 0.1)
				(type default)
			)
			(layer "F.Fab")
		)
		(fp_line
			(start 0.12065 -0.2794)
			(end 0.12065 -0.3048)
			(stroke
				(width 0.1)
				(type default)
			)
			(layer "F.Fab")
		)
		(fp_line
			(start 0.12065 -0.3048)
			(end 0.67945 -0.3048)
			(stroke
				(width 0.1)
				(type default)
			)
			(layer "F.Fab")
		)
		(fp_line
			(start 0.120396 0.3048)
			(end 0.120396 0.2794)
			(stroke
				(width 0.1)
				(type default)
			)
			(layer "F.Fab")
		)
		(fp_line
			(start 0.120396 0.2794)
			(end -0.12065 0.2794)
			(stroke
				(width 0.1)
				(type default)
			)
			(layer "F.Fab")
		)
		(fp_line
			(start -0.12065 0.3048)
			(end -0.67945 0.3048)
			(stroke
				(width 0.1)
				(type default)
			)
			(layer "F.Fab")
		)
		(fp_line
			(start -0.12065 0.2794)
			(end -0.12065 0.3048)
			(stroke
				(width 0.1)
				(type default)
			)
			(layer "F.Fab")
		)
		(fp_line
			(start -0.12065 -0.2794)
			(end 0.12065 -0.2794)
			(stroke
				(width 0.1)
				(type default)
			)
			(layer "F.Fab")
		)
		(fp_line
			(start -0.12065 -0.305054)
			(end -0.12065 -0.2794)
			(stroke
				(width 0.1)
				(type default)
			)
			(layer "F.Fab")
		)
		(fp_line
			(start -0.67945 0.3048)
			(end -0.67945 -0.305054)
			(stroke
				(width 0.1)
				(type default)
			)
			(layer "F.Fab")
		)
		(fp_line
			(start -0.67945 -0.305054)
			(end -0.12065 -0.305054)
			(stroke
				(width 0.1)
				(type default)
			)
			(layer "F.Fab")
		)
		(pad "1" smd circle
			(at -0.40005 0 180)
			(size 0 0)
			(layers "F.Cu" "F.Mask" "F.Paste")
			(net "PCA9555_0_PEX1_A2")
		)
		(pad "2" smd circle
			(at 0.40005 0 180)
			(size 0 0)
			(layers "F.Cu" "F.Mask" "F.Paste")
			(net "P3V3_AUX")
		)
	)
	(footprint ""
		(layer "F.Cu")
		(at 46.434502 -34.546286 180)
		(property "Reference" "C73"
			(at 0 0 180)
			(layer "F.SilkS")
			(hide yes)
			(effects
				(font
					(size 1.27 1.27)
				)
			)
		)
		(property "Value" ""
			(at 0 0 180)
			(layer "F.Fab")
			(effects
				(font
					(size 1.27 1.27)
				)
			)
		)
		(duplicate_pad_numbers_are_jumpers no)
		(fp_line
			(start 0.299974 0.150114)
			(end -0.299974 0.150114)
			(stroke
				(width 0.1)
				(type default)
			)
			(layer "F.Fab")
		)
		(fp_line
			(start 0.299974 -0.150114)
			(end 0.299974 0.150114)
			(stroke
				(width 0.1)
				(type default)
			)
			(layer "F.Fab")
		)
		(fp_line
			(start -0.299974 0.150114)
			(end -0.299974 -0.150114)
			(stroke
				(width 0.1)
				(type default)
			)
			(layer "F.Fab")
		)
		(fp_line
			(start -0.299974 -0.150114)
			(end 0.299974 -0.150114)
			(stroke
				(width 0.1)
				(type default)
			)
			(layer "F.Fab")
		)
		(pad "1" smd rect
			(at -0.2667 0 180)
			(size 0.3048 0.381)
			(layers "F.Cu" "F.Mask" "F.Paste")
			(net "P5E_PEX0_STN2_TX_DP<43>")
		)
		(pad "2" smd rect
			(at 0.2667 0 180)
			(size 0.3048 0.381)
			(layers "F.Cu" "F.Mask" "F.Paste")
			(net "P5E_PEX0_STN2_TX_C_DP<43>")
		)
	)
	(footprint ""
		(layer "F.Cu")
		(at 239.813338 -137.344404 180)
		(property "Reference" "PR194"
			(at 0 0 180)
			(layer "F.SilkS")
			(hide yes)
			(effects
				(font
					(size 1.27 1.27)
				)
			)
		)
		(property "Value" ""
			(at 0 0 180)
			(layer "F.Fab")
			(effects
				(font
					(size 1.27 1.27)
				)
			)
		)
		(duplicate_pad_numbers_are_jumpers no)
		(fp_line
			(start 0.7874 0.4064)
			(end -0.7874 0.4064)
			(stroke
				(width 0.1524)
				(type default)
			)
			(layer "F.SilkS")
		)
		(fp_line
			(start 0.7874 -0.4064)
			(end 0.7874 0.4064)
			(stroke
				(width 0.1524)
				(type default)
			)
			(layer "F.SilkS")
		)
		(fp_line
			(start -0.7874 0.4064)
			(end -0.7874 -0.4064)
			(stroke
				(width 0.1524)
				(type default)
			)
			(layer "F.SilkS")
		)
		(fp_line
			(start -0.7874 -0.4064)
			(end 0.7874 -0.4064)
			(stroke
				(width 0.1524)
				(type default)
			)
			(layer "F.SilkS")
		)
		(fp_line
			(start 0.67945 0.3048)
			(end 0.120396 0.3048)
			(stroke
				(width 0.1)
				(type default)
			)
			(layer "F.Fab")
		)
		(fp_line
			(start 0.67945 -0.3048)
			(end 0.67945 0.3048)
			(stroke
				(width 0.1)
				(type default)
			)
			(layer "F.Fab")
		)
		(fp_line
			(start 0.12065 -0.2794)
			(end 0.12065 -0.3048)
			(stroke
				(width 0.1)
				(type default)
			)
			(layer "F.Fab")
		)
		(fp_line
			(start 0.12065 -0.3048)
			(end 0.67945 -0.3048)
			(stroke
				(width 0.1)
				(type default)
			)
			(layer "F.Fab")
		)
		(fp_line
			(start 0.120396 0.3048)
			(end 0.120396 0.2794)
			(stroke
				(width 0.1)
				(type default)
			)
			(layer "F.Fab")
		)
		(fp_line
			(start 0.120396 0.2794)
			(end -0.12065 0.2794)
			(stroke
				(width 0.1)
				(type default)
			)
			(layer "F.Fab")
		)
		(fp_line
			(start -0.12065 0.3048)
			(end -0.67945 0.3048)
			(stroke
				(width 0.1)
				(type default)
			)
			(layer "F.Fab")
		)
		(fp_line
			(start -0.12065 0.2794)
			(end -0.12065 0.3048)
			(stroke
				(width 0.1)
				(type default)
			)
			(layer "F.Fab")
		)
		(fp_line
			(start -0.12065 -0.2794)
			(end 0.12065 -0.2794)
			(stroke
				(width 0.1)
				(type default)
			)
			(layer "F.Fab")
		)
		(fp_line
			(start -0.12065 -0.305054)
			(end -0.12065 -0.2794)
			(stroke
				(width 0.1)
				(type default)
			)
			(layer "F.Fab")
		)
		(fp_line
			(start -0.67945 0.3048)
			(end -0.67945 -0.305054)
			(stroke
				(width 0.1)
				(type default)
			)
			(layer "F.Fab")
		)
		(fp_line
			(start -0.67945 -0.305054)
			(end -0.12065 -0.305054)
			(stroke
				(width 0.1)
				(type default)
			)
			(layer "F.Fab")
		)
		(pad "1" smd circle
			(at -0.40005 0 180)
			(size 0 0)
			(layers "F.Cu" "F.Mask" "F.Paste")
			(net "P12V_NIC4_OCP")
		)
		(pad "2" smd circle
			(at 0.40005 0 180)
			(size 0 0)
			(layers "F.Cu" "F.Mask" "F.Paste")
			(net "GND")
		)
	)
	(footprint ""
		(layer "F.Cu")
		(at 30.373828 -27.006296 -90)
		(property "Reference" "PC676"
			(at 0 0 270)
			(layer "F.SilkS")
			(hide yes)
			(effects
				(font
					(size 1.27 1.27)
				)
			)
		)
		(property "Value" ""
			(at 0 0 270)
			(layer "F.Fab")
			(effects
				(font
					(size 1.27 1.27)
				)
			)
		)
		(duplicate_pad_numbers_are_jumpers no)
		(fp_line
			(start -0.7874 0.4064)
			(end -0.7874 -0.4064)
			(stroke
				(width 0.1524)
				(type default)
			)
			(layer "F.SilkS")
		)
		(fp_line
			(start 0.7874 0.4064)
			(end -0.7874 0.4064)
			(stroke
				(width 0.1524)
				(type default)
			)
			(layer "F.SilkS")
		)
		(fp_line
			(start -0.7874 -0.4064)
			(end 0.7874 -0.4064)
			(stroke
				(width 0.1524)
				(type default)
			)
			(layer "F.SilkS")
		)
		(fp_line
			(start 0.7874 -0.4064)
			(end 0.7874 0.4064)
			(stroke
				(width 0.1524)
				(type default)
			)
			(layer "F.SilkS")
		)
		(fp_line
			(start -0.67945 0.3048)
			(end -0.67945 -0.305054)
			(stroke
				(width 0.1)
				(type default)
			)
			(layer "F.Fab")
		)
		(fp_line
			(start -0.12065 0.3048)
			(end -0.67945 0.3048)
			(stroke
				(width 0.1)
				(type default)
			)
			(layer "F.Fab")
		)
		(fp_line
			(start 0.120396 0.3048)
			(end 0.120396 0.2794)
			(stroke
				(width 0.1)
				(type default)
			)
			(layer "F.Fab")
		)
		(fp_line
			(start 0.67945 0.3048)
			(end 0.120396 0.3048)
			(stroke
				(width 0.1)
				(type default)
			)
			(layer "F.Fab")
		)
		(fp_line
			(start -0.12065 0.2794)
			(end -0.12065 0.3048)
			(stroke
				(width 0.1)
				(type default)
			)
			(layer "F.Fab")
		)
		(fp_line
			(start 0.120396 0.2794)
			(end -0.12065 0.2794)
			(stroke
				(width 0.1)
				(type default)
			)
			(layer "F.Fab")
		)
		(fp_line
			(start -0.12065 -0.2794)
			(end 0.12065 -0.2794)
			(stroke
				(width 0.1)
				(type default)
			)
			(layer "F.Fab")
		)
		(fp_line
			(start 0.12065 -0.2794)
			(end 0.12065 -0.3048)
			(stroke
				(width 0.1)
				(type default)
			)
			(layer "F.Fab")
		)
		(fp_line
			(start 0.12065 -0.3048)
			(end 0.67945 -0.3048)
			(stroke
				(width 0.1)
				(type default)
			)
			(layer "F.Fab")
		)
		(fp_line
			(start 0.67945 -0.3048)
			(end 0.67945 0.3048)
			(stroke
				(width 0.1)
				(type default)
			)
			(layer "F.Fab")
		)
		(fp_line
			(start -0.67945 -0.305054)
			(end -0.12065 -0.305054)
			(stroke
				(width 0.1)
				(type default)
			)
			(layer "F.Fab")
		)
		(fp_line
			(start -0.12065 -0.305054)
			(end -0.12065 -0.2794)
			(stroke
				(width 0.1)
				(type default)
			)
			(layer "F.Fab")
		)
		(pad "1" smd circle
			(at -0.40005 0 270)
			(size 0 0)
			(layers "F.Cu" "F.Mask" "F.Paste")
			(net "P3V3_SSD1_CO_MODE")
		)
		(pad "2" smd circle
			(at 0.40005 0 270)
			(size 0 0)
			(layers "F.Cu" "F.Mask" "F.Paste")
			(net "GND")
		)
	)
	(footprint ""
		(layer "F.Cu")
		(at 13.802106 -378.325888 90)
		(property "Reference" "R6751"
			(at 0 0 90)
			(layer "F.SilkS")
			(hide yes)
			(effects
				(font
					(size 1.27 1.27)
				)
			)
		)
		(property "Value" ""
			(at 0 0 90)
			(layer "F.Fab")
			(effects
				(font
					(size 1.27 1.27)
				)
			)
		)
		(duplicate_pad_numbers_are_jumpers no)
		(fp_line
			(start 0.7874 -0.4064)
			(end 0.7874 0.4064)
			(stroke
				(width 0.1524)
				(type default)
			)
			(layer "F.SilkS")
		)
		(fp_line
			(start -0.395986 -0.4064)
			(end 0.7874 -0.4064)
			(stroke
				(width 0.1524)
				(type default)
			)
			(layer "F.SilkS")
		)
		(fp_line
			(start 0.7874 0.4064)
			(end -0.358902 0.4064)
			(stroke
				(width 0.1524)
				(type default)
			)
			(layer "F.SilkS")
		)
		(fp_line
			(start -0.12065 -0.305054)
			(end -0.12065 -0.2794)
			(stroke
				(width 0.1)
				(type default)
			)
			(layer "F.Fab")
		)
		(fp_line
			(start -0.67945 -0.305054)
			(end -0.12065 -0.305054)
			(stroke
				(width 0.1)
				(type default)
			)
			(layer "F.Fab")
		)
		(fp_line
			(start 0.67945 -0.3048)
			(end 0.67945 0.3048)
			(stroke
				(width 0.1)
				(type default)
			)
			(layer "F.Fab")
		)
		(fp_line
			(start 0.12065 -0.3048)
			(end 0.67945 -0.3048)
			(stroke
				(width 0.1)
				(type default)
			)
			(layer "F.Fab")
		)
		(fp_line
			(start 0.12065 -0.2794)
			(end 0.12065 -0.3048)
			(stroke
				(width 0.1)
				(type default)
			)
			(layer "F.Fab")
		)
		(fp_line
			(start -0.12065 -0.2794)
			(end 0.12065 -0.2794)
			(stroke
				(width 0.1)
				(type default)
			)
			(layer "F.Fab")
		)
		(fp_line
			(start 0.120396 0.2794)
			(end -0.12065 0.2794)
			(stroke
				(width 0.1)
				(type default)
			)
			(layer "F.Fab")
		)
		(fp_line
			(start -0.12065 0.2794)
			(end -0.12065 0.3048)
			(stroke
				(width 0.1)
				(type default)
			)
			(layer "F.Fab")
		)
		(fp_line
			(start 0.67945 0.3048)
			(end 0.120396 0.3048)
			(stroke
				(width 0.1)
				(type default)
			)
			(layer "F.Fab")
		)
		(fp_line
			(start 0.120396 0.3048)
			(end 0.120396 0.2794)
			(stroke
				(width 0.1)
				(type default)
			)
			(layer "F.Fab")
		)
		(fp_line
			(start -0.12065 0.3048)
			(end -0.67945 0.3048)
			(stroke
				(width 0.1)
				(type default)
			)
			(layer "F.Fab")
		)
		(fp_line
			(start -0.67945 0.3048)
			(end -0.67945 -0.305054)
			(stroke
				(width 0.1)
				(type default)
			)
			(layer "F.Fab")
		)
		(pad "1" smd circle
			(at -0.40005 0 90)
			(size 0 0)
			(layers "F.Cu" "F.Mask" "F.Paste")
			(net "USB2_GPU_HMC_USB8042_DN")
		)
		(pad "2" smd circle
			(at 0.40005 0 90)
			(size 0 0)
			(layers "F.Cu" "F.Mask" "F.Paste")
			(net "GND")
		)
	)
)
